(kicad_pcb
	(version 20260206)
	(generator "pcbnew")
	(generator_version "10.0")
	(general
		(thickness 1.6)
		(legacy_teardrops no)
	)
	(paper "A4")
	(title_block
		(title "04192023_DAF0TMB3IC0_F0TG_MB_C_brd_V02_OCP.brd")
		(comment 1 "Grand Teton / footprint 2352 of 8354 (J1), pads 1-113 of 291")
	)
	(layers
		(0 "F.Cu" signal "TOP")
		(4 "In1.Cu" signal "GND")
		(6 "In2.Cu" signal "IN1")
		(8 "In3.Cu" signal "GND1")
		(10 "In4.Cu" signal "IN2")
		(12 "In5.Cu" signal "GND2")
		(14 "In6.Cu" signal "IN3")
		(16 "In7.Cu" signal "GND3")
		(18 "In8.Cu" signal "VCC")
		(20 "In9.Cu" signal "VCC1")
		(22 "In10.Cu" signal "GND4")
		(24 "In11.Cu" signal "IN4")
		(26 "In12.Cu" signal "GND5")
		(28 "In13.Cu" signal "IN5")
		(30 "In14.Cu" signal "GND6")
		(32 "In15.Cu" signal "IN6")
		(34 "In16.Cu" signal "GND7")
		(2 "B.Cu" signal "BOTTOM")
		(9 "F.Adhes" user "F.Adhesive")
		(11 "B.Adhes" user "B.Adhesive")
		(13 "F.Paste" user "Package Geometry/Pastemask Top")
		(15 "B.Paste" user "Package Geometry/Pastemask Bottom")
		(5 "F.SilkS" user "Ref Des/Silkscreen Top")
		(7 "B.SilkS" user "Ref Des/Silkscreen Bottom")
		(1 "F.Mask" user "Board Geometry/Soldermask Top")
		(3 "B.Mask" user "Board Geometry/Soldermask Bottom")
		(17 "Dwgs.User" user "User.Drawings")
		(19 "Cmts.User" user "User.Comments")
		(21 "Eco1.User" user "User.Eco1")
		(23 "Eco2.User" user "User.Eco2")
		(25 "Edge.Cuts" user "Board Geometry/Outline")
		(27 "Margin" user)
		(31 "F.CrtYd" user "Package Geometry/Place Bound Top")
		(29 "B.CrtYd" user "Package Geometry/Place Bound Bottom")
		(35 "F.Fab" user "Ref Des/Assembly Top")
		(33 "B.Fab" user "Ref Des/Assembly Bottom")
	)
	(footprint ""
		(layer "F.Cu")
		(at 305.31816 -255.560068 180)
		(property "Reference" "J1"
			(at -2.2098 -81.984088 0)
			(unlocked yes)
			(layer "F.SilkS")
			(effects
				(font
					(size 0.7874 0.5842)
					(thickness 0.1524)
				)
			)
		)
		(property "Value" ""
			(at 0 0 180)
			(layer "F.Fab")
			(effects
				(font
					(size 1.27 1.27)
				)
			)
		)
		(duplicate_pad_numbers_are_jumpers no)
		(pad "1" smd rect
			(at -2.050034 -63.324994 90)
			(size 0.519938 1.4986)
			(layers "F.Cu" "F.Mask" "F.Paste")
			(net "P12V_MEM_CPU0")
		)
		(pad "2" smd rect
			(at -2.050034 -62.47511 90)
			(size 0.519938 1.4986)
			(layers "F.Cu" "F.Mask" "F.Paste")
			(net "Net_2249")
		)
		(pad "3" smd rect
			(at -2.050034 -61.624972 90)
			(size 0.519938 1.4986)
			(layers "F.Cu" "F.Mask" "F.Paste")
			(net "P3V3_AUX")
		)
		(pad "4" smd rect
			(at -2.050034 -60.775088 90)
			(size 0.519938 1.4986)
			(layers "F.Cu" "F.Mask" "F.Paste")
			(net "I3C_SPD_DDRA_CPU0_SCL")
		)
		(pad "5" smd rect
			(at -2.050034 -59.92495 90)
			(size 0.519938 1.4986)
			(layers "F.Cu" "F.Mask" "F.Paste")
			(net "I3C_SPD_DDRA_CPU0_SDA")
		)
		(pad "6" smd rect
			(at -2.050034 -59.075066 90)
			(size 0.519938 1.4986)
			(layers "F.Cu" "F.Mask" "F.Paste")
			(net "GND")
		)
		(pad "7" smd rect
			(at -2.050034 -58.224928 90)
			(size 0.519938 1.4986)
			(layers "F.Cu" "F.Mask" "F.Paste")
			(net "M_A_CPU0_SA_DQ<0>")
		)
		(pad "8" smd rect
			(at -2.050034 -57.375044 90)
			(size 0.519938 1.4986)
			(layers "F.Cu" "F.Mask" "F.Paste")
			(net "GND")
		)
		(pad "9" smd rect
			(at -2.050034 -56.524906 90)
			(size 0.519938 1.4986)
			(layers "F.Cu" "F.Mask" "F.Paste")
			(net "M_A_CPU0_SA_DQ<1>")
		)
		(pad "10" smd rect
			(at -2.050034 -55.675022 90)
			(size 0.519938 1.4986)
			(layers "F.Cu" "F.Mask" "F.Paste")
			(net "GND")
		)
		(pad "11" smd rect
			(at -2.050034 -54.824884 90)
			(size 0.519938 1.4986)
			(layers "F.Cu" "F.Mask" "F.Paste")
			(net "M_A_CPU0_SA_DQS_DP<0>")
		)
		(pad "12" smd rect
			(at -2.050034 -53.975 90)
			(size 0.519938 1.4986)
			(layers "F.Cu" "F.Mask" "F.Paste")
			(net "M_A_CPU0_SA_DQS_DN<0>")
		)
		(pad "13" smd rect
			(at -2.050034 -53.125116 90)
			(size 0.519938 1.4986)
			(layers "F.Cu" "F.Mask" "F.Paste")
			(net "GND")
		)
		(pad "14" smd rect
			(at -2.050034 -52.274978 90)
			(size 0.519938 1.4986)
			(layers "F.Cu" "F.Mask" "F.Paste")
			(net "M_A_CPU0_SA_DQ<4>")
		)
		(pad "15" smd rect
			(at -2.050034 -51.425094 90)
			(size 0.519938 1.4986)
			(layers "F.Cu" "F.Mask" "F.Paste")
			(net "GND")
		)
		(pad "16" smd rect
			(at -2.050034 -50.574956 90)
			(size 0.519938 1.4986)
			(layers "F.Cu" "F.Mask" "F.Paste")
			(net "M_A_CPU0_SA_DQ<5>")
		)
		(pad "17" smd rect
			(at -2.050034 -49.725072 90)
			(size 0.519938 1.4986)
			(layers "F.Cu" "F.Mask" "F.Paste")
			(net "GND")
		)
		(pad "18" smd rect
			(at -2.050034 -48.874934 90)
			(size 0.519938 1.4986)
			(layers "F.Cu" "F.Mask" "F.Paste")
			(net "M_A_CPU0_SA_DQ<8>")
		)
		(pad "19" smd rect
			(at -2.050034 -48.02505 90)
			(size 0.519938 1.4986)
			(layers "F.Cu" "F.Mask" "F.Paste")
			(net "GND")
		)
		(pad "20" smd rect
			(at -2.050034 -47.174912 90)
			(size 0.519938 1.4986)
			(layers "F.Cu" "F.Mask" "F.Paste")
			(net "M_A_CPU0_SA_DQ<9>")
		)
		(pad "21" smd rect
			(at -2.050034 -46.325028 90)
			(size 0.519938 1.4986)
			(layers "F.Cu" "F.Mask" "F.Paste")
			(net "GND")
		)
		(pad "22" smd rect
			(at -2.050034 -45.47489 90)
			(size 0.519938 1.4986)
			(layers "F.Cu" "F.Mask" "F.Paste")
			(net "M_A_CPU0_SA_DQS_DP<1>")
		)
		(pad "23" smd rect
			(at -2.050034 -44.625006 90)
			(size 0.519938 1.4986)
			(layers "F.Cu" "F.Mask" "F.Paste")
			(net "M_A_CPU0_SA_DQS_DN<1>")
		)
		(pad "24" smd rect
			(at -2.050034 -43.775122 90)
			(size 0.519938 1.4986)
			(layers "F.Cu" "F.Mask" "F.Paste")
			(net "GND")
		)
		(pad "25" smd rect
			(at -2.050034 -42.924984 90)
			(size 0.519938 1.4986)
			(layers "F.Cu" "F.Mask" "F.Paste")
			(net "M_A_CPU0_SA_DQ<12>")
		)
		(pad "26" smd rect
			(at -2.050034 -42.0751 90)
			(size 0.519938 1.4986)
			(layers "F.Cu" "F.Mask" "F.Paste")
			(net "GND")
		)
		(pad "27" smd rect
			(at -2.050034 -41.224962 90)
			(size 0.519938 1.4986)
			(layers "F.Cu" "F.Mask" "F.Paste")
			(net "M_A_CPU0_SA_DQ<13>")
		)
		(pad "28" smd rect
			(at -2.050034 -40.375078 90)
			(size 0.519938 1.4986)
			(layers "F.Cu" "F.Mask" "F.Paste")
			(net "GND")
		)
		(pad "29" smd rect
			(at -2.050034 -39.52494 90)
			(size 0.519938 1.4986)
			(layers "F.Cu" "F.Mask" "F.Paste")
			(net "M_A_CPU0_SA_DQ<16>")
		)
		(pad "30" smd rect
			(at -2.050034 -38.675056 90)
			(size 0.519938 1.4986)
			(layers "F.Cu" "F.Mask" "F.Paste")
			(net "GND")
		)
		(pad "31" smd rect
			(at -2.050034 -37.824918 90)
			(size 0.519938 1.4986)
			(layers "F.Cu" "F.Mask" "F.Paste")
			(net "M_A_CPU0_SA_DQ<17>")
		)
		(pad "32" smd rect
			(at -2.050034 -36.975034 90)
			(size 0.519938 1.4986)
			(layers "F.Cu" "F.Mask" "F.Paste")
			(net "GND")
		)
		(pad "33" smd rect
			(at -2.050034 -36.124896 90)
			(size 0.519938 1.4986)
			(layers "F.Cu" "F.Mask" "F.Paste")
			(net "M_A_CPU0_SA_DQS_DP<2>")
		)
		(pad "34" smd rect
			(at -2.050034 -35.275012 90)
			(size 0.519938 1.4986)
			(layers "F.Cu" "F.Mask" "F.Paste")
			(net "M_A_CPU0_SA_DQS_DN<2>")
		)
		(pad "35" smd rect
			(at -2.050034 -34.425128 90)
			(size 0.519938 1.4986)
			(layers "F.Cu" "F.Mask" "F.Paste")
			(net "GND")
		)
		(pad "36" smd rect
			(at -2.050034 -33.57499 90)
			(size 0.519938 1.4986)
			(layers "F.Cu" "F.Mask" "F.Paste")
			(net "M_A_CPU0_SA_DQ<20>")
		)
		(pad "37" smd rect
			(at -2.050034 -32.725106 90)
			(size 0.519938 1.4986)
			(layers "F.Cu" "F.Mask" "F.Paste")
			(net "GND")
		)
		(pad "38" smd rect
			(at -2.050034 -31.874968 90)
			(size 0.519938 1.4986)
			(layers "F.Cu" "F.Mask" "F.Paste")
			(net "M_A_CPU0_SA_DQ<21>")
		)
		(pad "39" smd rect
			(at -2.050034 -31.025084 90)
			(size 0.519938 1.4986)
			(layers "F.Cu" "F.Mask" "F.Paste")
			(net "GND")
		)
		(pad "40" smd rect
			(at -2.050034 -30.174946 90)
			(size 0.519938 1.4986)
			(layers "F.Cu" "F.Mask" "F.Paste")
			(net "M_A_CPU0_SA_DQ<24>")
		)
		(pad "41" smd rect
			(at -2.050034 -29.325062 90)
			(size 0.519938 1.4986)
			(layers "F.Cu" "F.Mask" "F.Paste")
			(net "GND")
		)
		(pad "42" smd rect
			(at -2.050034 -28.474924 90)
			(size 0.519938 1.4986)
			(layers "F.Cu" "F.Mask" "F.Paste")
			(net "M_A_CPU0_SA_DQ<25>")
		)
		(pad "43" smd rect
			(at -2.050034 -27.62504 90)
			(size 0.519938 1.4986)
			(layers "F.Cu" "F.Mask" "F.Paste")
			(net "GND")
		)
		(pad "44" smd rect
			(at -2.050034 -26.774902 90)
			(size 0.519938 1.4986)
			(layers "F.Cu" "F.Mask" "F.Paste")
			(net "M_A_CPU0_SA_DQS_DP<3>")
		)
		(pad "45" smd rect
			(at -2.050034 -25.925018 90)
			(size 0.519938 1.4986)
			(layers "F.Cu" "F.Mask" "F.Paste")
			(net "M_A_CPU0_SA_DQS_DN<3>")
		)
		(pad "46" smd rect
			(at -2.050034 -25.07488 90)
			(size 0.519938 1.4986)
			(layers "F.Cu" "F.Mask" "F.Paste")
			(net "GND")
		)
		(pad "47" smd rect
			(at -2.050034 -24.224996 90)
			(size 0.519938 1.4986)
			(layers "F.Cu" "F.Mask" "F.Paste")
			(net "M_A_CPU0_SA_DQ<28>")
		)
		(pad "48" smd rect
			(at -2.050034 -23.375112 90)
			(size 0.519938 1.4986)
			(layers "F.Cu" "F.Mask" "F.Paste")
			(net "GND")
		)
		(pad "49" smd rect
			(at -2.050034 -22.524974 90)
			(size 0.519938 1.4986)
			(layers "F.Cu" "F.Mask" "F.Paste")
			(net "M_A_CPU0_SA_DQ<29>")
		)
		(pad "50" smd rect
			(at -2.050034 -21.67509 90)
			(size 0.519938 1.4986)
			(layers "F.Cu" "F.Mask" "F.Paste")
			(net "GND")
		)
		(pad "51" smd rect
			(at -2.050034 -20.824952 90)
			(size 0.519938 1.4986)
			(layers "F.Cu" "F.Mask" "F.Paste")
			(net "M_A_CPU0_SA_CB<0>")
		)
		(pad "52" smd rect
			(at -2.050034 -19.975068 90)
			(size 0.519938 1.4986)
			(layers "F.Cu" "F.Mask" "F.Paste")
			(net "GND")
		)
		(pad "53" smd rect
			(at -2.050034 -19.12493 90)
			(size 0.519938 1.4986)
			(layers "F.Cu" "F.Mask" "F.Paste")
			(net "M_A_CPU0_SA_CB<1>")
		)
		(pad "54" smd rect
			(at -2.050034 -18.275046 90)
			(size 0.519938 1.4986)
			(layers "F.Cu" "F.Mask" "F.Paste")
			(net "GND")
		)
		(pad "55" smd rect
			(at -2.050034 -17.424908 90)
			(size 0.519938 1.4986)
			(layers "F.Cu" "F.Mask" "F.Paste")
			(net "M_A_CPU0_SA_DQS_DP<4>")
		)
		(pad "56" smd rect
			(at -2.050034 -16.575024 90)
			(size 0.519938 1.4986)
			(layers "F.Cu" "F.Mask" "F.Paste")
			(net "M_A_CPU0_SA_DQS_DN<4>")
		)
		(pad "57" smd rect
			(at -2.050034 -15.724886 90)
			(size 0.519938 1.4986)
			(layers "F.Cu" "F.Mask" "F.Paste")
			(net "GND")
		)
		(pad "58" smd rect
			(at -2.050034 -14.875002 90)
			(size 0.519938 1.4986)
			(layers "F.Cu" "F.Mask" "F.Paste")
			(net "M_A_CPU0_SA_CB<4>")
		)
		(pad "59" smd rect
			(at -2.050034 -14.025118 90)
			(size 0.519938 1.4986)
			(layers "F.Cu" "F.Mask" "F.Paste")
			(net "GND")
		)
		(pad "60" smd rect
			(at -2.050034 -13.17498 90)
			(size 0.519938 1.4986)
			(layers "F.Cu" "F.Mask" "F.Paste")
			(net "M_A_CPU0_SA_CB<5>")
		)
		(pad "61" smd rect
			(at -2.050034 -12.325096 90)
			(size 0.519938 1.4986)
			(layers "F.Cu" "F.Mask" "F.Paste")
			(net "GND")
		)
		(pad "62" smd rect
			(at -2.050034 -11.474958 90)
			(size 0.519938 1.4986)
			(layers "F.Cu" "F.Mask" "F.Paste")
			(net "M_A_CPU0_ALERT_N")
		)
		(pad "63" smd rect
			(at -2.050034 -10.625074 90)
			(size 0.519938 1.4986)
			(layers "F.Cu" "F.Mask" "F.Paste")
			(net "GND")
		)
		(pad "64" smd rect
			(at -2.050034 -9.774936 90)
			(size 0.519938 1.4986)
			(layers "F.Cu" "F.Mask" "F.Paste")
			(net "M_A_CPU0_SA_CS_N<0>")
		)
		(pad "65" smd rect
			(at -2.050034 -8.925052 90)
			(size 0.519938 1.4986)
			(layers "F.Cu" "F.Mask" "F.Paste")
			(net "GND")
		)
		(pad "66" smd rect
			(at -2.050034 -8.074914 90)
			(size 0.519938 1.4986)
			(layers "F.Cu" "F.Mask" "F.Paste")
			(net "M_A_CPU0_SA_CA<0>")
		)
		(pad "67" smd rect
			(at -2.050034 -7.22503 90)
			(size 0.519938 1.4986)
			(layers "F.Cu" "F.Mask" "F.Paste")
			(net "GND")
		)
		(pad "68" smd rect
			(at -2.050034 -6.374892 90)
			(size 0.519938 1.4986)
			(layers "F.Cu" "F.Mask" "F.Paste")
			(net "M_A_CPU0_SA_CA<2>")
		)
		(pad "69" smd rect
			(at -2.050034 -5.525008 90)
			(size 0.519938 1.4986)
			(layers "F.Cu" "F.Mask" "F.Paste")
			(net "GND")
		)
		(pad "70" smd rect
			(at -2.050034 -4.675124 90)
			(size 0.519938 1.4986)
			(layers "F.Cu" "F.Mask" "F.Paste")
			(net "M_A_CPU0_SA_CA<4>")
		)
		(pad "71" smd rect
			(at -2.050034 -3.824986 90)
			(size 0.519938 1.4986)
			(layers "F.Cu" "F.Mask" "F.Paste")
			(net "GND")
		)
		(pad "72" smd rect
			(at -2.050034 -2.975102 90)
			(size 0.519938 1.4986)
			(layers "F.Cu" "F.Mask" "F.Paste")
			(net "M_A_CPU0_SA_CA<6>")
		)
		(pad "73" smd rect
			(at -2.050034 -2.124964 90)
			(size 0.519938 1.4986)
			(layers "F.Cu" "F.Mask" "F.Paste")
			(net "GND")
		)
		(pad "74" smd rect
			(at -2.050034 -1.27508 90)
			(size 0.519938 1.4986)
			(layers "F.Cu" "F.Mask" "F.Paste")
			(net "M_A_CPU0_SA_PAR")
		)
		(pad "75" smd rect
			(at -2.050034 -0.424942 90)
			(size 0.519938 1.4986)
			(layers "F.Cu" "F.Mask" "F.Paste")
			(net "GND")
		)
		(pad "76" smd rect
			(at -2.050034 5.525008 90)
			(size 0.519938 1.4986)
			(layers "F.Cu" "F.Mask" "F.Paste")
			(net "M_A_CPU0_SB_CA<0>")
		)
		(pad "77" smd rect
			(at -2.050034 6.374892 90)
			(size 0.519938 1.4986)
			(layers "F.Cu" "F.Mask" "F.Paste")
			(net "GND")
		)
		(pad "78" smd rect
			(at -2.050034 7.22503 90)
			(size 0.519938 1.4986)
			(layers "F.Cu" "F.Mask" "F.Paste")
			(net "M_A_CPU0_SB_CA<2>")
		)
		(pad "79" smd rect
			(at -2.050034 8.074914 90)
			(size 0.519938 1.4986)
			(layers "F.Cu" "F.Mask" "F.Paste")
			(net "GND")
		)
		(pad "80" smd rect
			(at -2.050034 8.925052 90)
			(size 0.519938 1.4986)
			(layers "F.Cu" "F.Mask" "F.Paste")
			(net "M_A_CPU0_SB_CA<4>")
		)
		(pad "81" smd rect
			(at -2.050034 9.774936 90)
			(size 0.519938 1.4986)
			(layers "F.Cu" "F.Mask" "F.Paste")
			(net "GND")
		)
		(pad "82" smd rect
			(at -2.050034 10.625074 90)
			(size 0.519938 1.4986)
			(layers "F.Cu" "F.Mask" "F.Paste")
			(net "M_A_CPU0_SB_CA<6>")
		)
		(pad "83" smd rect
			(at -2.050034 11.474958 90)
			(size 0.519938 1.4986)
			(layers "F.Cu" "F.Mask" "F.Paste")
			(net "GND")
		)
		(pad "84" smd rect
			(at -2.050034 12.325096 90)
			(size 0.519938 1.4986)
			(layers "F.Cu" "F.Mask" "F.Paste")
			(net "M_A_CPU0_SB_CS_N<0>")
		)
		(pad "85" smd rect
			(at -2.050034 13.17498 90)
			(size 0.519938 1.4986)
			(layers "F.Cu" "F.Mask" "F.Paste")
			(net "GND")
		)
		(pad "86" smd rect
			(at -2.050034 14.025118 90)
			(size 0.519938 1.4986)
			(layers "F.Cu" "F.Mask" "F.Paste")
			(net "M_A_CPU0_SA_RSP<0>")
		)
		(pad "87" smd rect
			(at -2.050034 14.875002 90)
			(size 0.519938 1.4986)
			(layers "F.Cu" "F.Mask" "F.Paste")
			(net "M_A_CPU0_SB_RSP<0>")
		)
		(pad "88" smd rect
			(at -2.050034 15.724886 90)
			(size 0.519938 1.4986)
			(layers "F.Cu" "F.Mask" "F.Paste")
			(net "GND")
		)
		(pad "89" smd rect
			(at -2.050034 16.575024 90)
			(size 0.519938 1.4986)
			(layers "F.Cu" "F.Mask" "F.Paste")
			(net "M_A_CPU0_SB_CB<4>")
		)
		(pad "90" smd rect
			(at -2.050034 17.424908 90)
			(size 0.519938 1.4986)
			(layers "F.Cu" "F.Mask" "F.Paste")
			(net "GND")
		)
		(pad "91" smd rect
			(at -2.050034 18.275046 90)
			(size 0.519938 1.4986)
			(layers "F.Cu" "F.Mask" "F.Paste")
			(net "M_A_CPU0_SB_CB<5>")
		)
		(pad "92" smd rect
			(at -2.050034 19.12493 90)
			(size 0.519938 1.4986)
			(layers "F.Cu" "F.Mask" "F.Paste")
			(net "GND")
		)
		(pad "93" smd rect
			(at -2.050034 19.975068 90)
			(size 0.519938 1.4986)
			(layers "F.Cu" "F.Mask" "F.Paste")
			(net "M_A_CPU0_SB_DQS_DP<9>")
		)
		(pad "94" smd rect
			(at -2.050034 20.824952 90)
			(size 0.519938 1.4986)
			(layers "F.Cu" "F.Mask" "F.Paste")
			(net "M_A_CPU0_SB_DQS_DN<9>")
		)
		(pad "95" smd rect
			(at -2.050034 21.67509 90)
			(size 0.519938 1.4986)
			(layers "F.Cu" "F.Mask" "F.Paste")
			(net "GND")
		)
		(pad "96" smd rect
			(at -2.050034 22.524974 90)
			(size 0.519938 1.4986)
			(layers "F.Cu" "F.Mask" "F.Paste")
			(net "M_A_CPU0_SB_CB<0>")
		)
		(pad "97" smd rect
			(at -2.050034 23.375112 90)
			(size 0.519938 1.4986)
			(layers "F.Cu" "F.Mask" "F.Paste")
			(net "GND")
		)
		(pad "98" smd rect
			(at -2.050034 24.224996 90)
			(size 0.519938 1.4986)
			(layers "F.Cu" "F.Mask" "F.Paste")
			(net "M_A_CPU0_SB_CB<1>")
		)
		(pad "99" smd rect
			(at -2.050034 25.07488 90)
			(size 0.519938 1.4986)
			(layers "F.Cu" "F.Mask" "F.Paste")
			(net "GND")
		)
		(pad "100" smd rect
			(at -2.050034 25.925018 90)
			(size 0.519938 1.4986)
			(layers "F.Cu" "F.Mask" "F.Paste")
			(net "M_A_CPU0_SB_DQ<0>")
		)
		(pad "101" smd rect
			(at -2.050034 26.774902 90)
			(size 0.519938 1.4986)
			(layers "F.Cu" "F.Mask" "F.Paste")
			(net "GND")
		)
		(pad "102" smd rect
			(at -2.050034 27.62504 90)
			(size 0.519938 1.4986)
			(layers "F.Cu" "F.Mask" "F.Paste")
			(net "M_A_CPU0_SB_DQ<1>")
		)
		(pad "103" smd rect
			(at -2.050034 28.474924 90)
			(size 0.519938 1.4986)
			(layers "F.Cu" "F.Mask" "F.Paste")
			(net "GND")
		)
		(pad "104" smd rect
			(at -2.050034 29.325062 90)
			(size 0.519938 1.4986)
			(layers "F.Cu" "F.Mask" "F.Paste")
			(net "M_A_CPU0_SB_DQS_DP<0>")
		)
		(pad "105" smd rect
			(at -2.050034 30.174946 90)
			(size 0.519938 1.4986)
			(layers "F.Cu" "F.Mask" "F.Paste")
			(net "M_A_CPU0_SB_DQS_DN<0>")
		)
		(pad "106" smd rect
			(at -2.050034 31.025084 90)
			(size 0.519938 1.4986)
			(layers "F.Cu" "F.Mask" "F.Paste")
			(net "GND")
		)
		(pad "107" smd rect
			(at -2.050034 31.874968 90)
			(size 0.519938 1.4986)
			(layers "F.Cu" "F.Mask" "F.Paste")
			(net "M_A_CPU0_SB_DQ<4>")
		)
		(pad "108" smd rect
			(at -2.050034 32.725106 90)
			(size 0.519938 1.4986)
			(layers "F.Cu" "F.Mask" "F.Paste")
			(net "GND")
		)
		(pad "109" smd rect
			(at -2.050034 33.57499 90)
			(size 0.519938 1.4986)
			(layers "F.Cu" "F.Mask" "F.Paste")
			(net "M_A_CPU0_SB_DQ<5>")
		)
		(pad "110" smd rect
			(at -2.050034 34.425128 90)
			(size 0.519938 1.4986)
			(layers "F.Cu" "F.Mask" "F.Paste")
			(net "GND")
		)
		(pad "111" smd rect
			(at -2.050034 35.275012 90)
			(size 0.519938 1.4986)
			(layers "F.Cu" "F.Mask" "F.Paste")
			(net "M_A_CPU0_SB_DQ<8>")
		)
		(pad "112" smd rect
			(at -2.050034 36.124896 90)
			(size 0.519938 1.4986)
			(layers "F.Cu" "F.Mask" "F.Paste")
			(net "GND")
		)
		(pad "113" smd rect
			(at -2.050034 36.975034 90)
			(size 0.519938 1.4986)
			(layers "F.Cu" "F.Mask" "F.Paste")
			(net "M_A_CPU0_SB_DQ<9>")
		)
	)
)
